# BASEBOARD_FAB2 (Tioga Pass) — schematic netlist excerpt (pin names and nets, part order shuffled) for the footprints in the layout excerpt that follows; sources: Cadence DE-HDL packaged netlist, KiCad conversion of Wiwynn_Tioga_Pass_MB.brd

C4D32  CAP_A  0.1UF 16V 10% X7R  pkg 0402V  page 213 : A = VR_PVCCIO_CPU1_VD12 ; B = GND
R12W5  665KR2B-GP  0.1%  pkg SMD-RG2  page 197 : \1\ = VR_PVDDQ_ABC_AIINSEN ; \2\ = VR_PVDDQ_ABC_VINSEN

(kicad_pcb
	(version 20260206)
	(generator "pcbnew")
	(generator_version "10.0")
	(general
		(thickness 1.6)
		(legacy_teardrops no)
	)
	(paper "A4")
	(title_block
		(title "Wiwynn_Tioga_Pass_MB.brd")
		(comment 1 "Tioga Pass / footprints 959-960 of 4770")
	)
	(layers
		(0 "F.Cu" signal "TOP")
		(4 "In1.Cu" signal "L2GND")
		(6 "In2.Cu" signal "L3")
		(8 "In3.Cu" signal "L4GND")
		(10 "In4.Cu" signal "L5")
		(12 "In5.Cu" signal "L6GND")
		(14 "In6.Cu" signal "L7VCC")
		(16 "In7.Cu" signal "L8VCC")
		(18 "In8.Cu" signal "L9GND")
		(20 "In9.Cu" signal "L10")
		(22 "In10.Cu" signal "L11GND")
		(24 "In11.Cu" signal "L12")
		(26 "In12.Cu" signal "L13GND")
		(2 "B.Cu" signal "BOTTOM")
		(9 "F.Adhes" user "F.Adhesive")
		(11 "B.Adhes" user "B.Adhesive")
		(13 "F.Paste" user "Package Geometry/Pastemask Top")
		(15 "B.Paste" user "Package Geometry/Pastemask Bottom")
		(5 "F.SilkS" user "Ref Des/Silkscreen Top")
		(7 "B.SilkS" user "Ref Des/Silkscreen Bottom")
		(1 "F.Mask" user "Board Geometry/Soldermask Top")
		(3 "B.Mask" user "Board Geometry/Soldermask Bottom")
		(17 "Dwgs.User" user "User.Drawings")
		(19 "Cmts.User" user "User.Comments")
		(21 "Eco1.User" user "User.Eco1")
		(23 "Eco2.User" user "User.Eco2")
		(25 "Edge.Cuts" user "Board Geometry/Outline")
		(27 "Margin" user)
		(31 "F.CrtYd" user "Package Geometry/Place Bound Top")
		(29 "B.CrtYd" user "Package Geometry/Place Bound Bottom")
		(35 "F.Fab" user "Ref Des/Assembly Top")
		(33 "B.Fab" user "Ref Des/Assembly Bottom")
	)
	(footprint ""
		(layer "F.Cu")
		(at 349.886016 -16.19631)
		(property "Reference" "R12W5"
			(at 0 0 0)
			(layer "F.SilkS")
			(hide yes)
			(effects
				(font
					(size 1.27 1.27)
				)
			)
		)
		(property "Value" "*"
			(at 0.064008 -4.108196 0)
			(unlocked yes)
			(layer "F.Fab")
			(hide yes)
			(effects
				(font
					(size 1.27 1.016)
					(thickness 0.1524)
				)
			)
		)
		(property "Device Type" "665KR2B-GP_SMD-RG2-665KR2B-GP,A"
			(at 0.064008 -5.632196 0)
			(unlocked yes)
			(layer "F.Fab")
			(hide yes)
			(effects
				(font
					(size 1.27 1.016)
					(thickness 0.1524)
				)
			)
		)
		(duplicate_pad_numbers_are_jumpers no)
		(fp_line
			(start -0.508 -0.9398)
			(end -0.508 0.9398)
			(stroke
				(width 0.1524)
				(type default)
			)
			(layer "F.SilkS")
		)
		(fp_line
			(start 0.508 -0.9398)
			(end -0.508 -0.9398)
			(stroke
				(width 0.1524)
				(type default)
			)
			(layer "F.SilkS")
		)
		(fp_rect
			(start -0.508 0.9398)
			(end 0.508 -0.9398)
			(stroke
				(width 0)
				(type default)
			)
			(fill no)
			(layer "F.CrtYd")
		)
		(fp_rect
			(start -0.508 0.9398)
			(end 0.508 -0.9398)
			(stroke
				(width 0)
				(type default)
			)
			(fill no)
			(layer "F.Fab")
		)
		(pad "1" smd custom
			(at 0 -0.4445)
			(size 0.1397 0.1397)
			(layers "F.Cu" "F.Mask" "F.Paste")
			(net "VR_PVDDQ_ABC_AIINSEN")
			(options
				(clearance outline)
				(anchor circle)
			)
			(primitives
				(gr_poly
					(pts
						(arc
							(start -0.1778 -0.2794)
							(mid -0.249642 -0.249642)
							(end -0.2794 -0.1778)
						)
						(arc
							(start -0.2794 0.1778)
							(mid -0.249642 0.249642)
							(end -0.1778 0.2794)
						)
						(arc
							(start 0.1778 0.2794)
							(mid 0.249642 0.249642)
							(end 0.2794 0.1778)
						)
						(arc
							(start 0.2794 -0.1778)
							(mid 0.249642 -0.249642)
							(end 0.1778 -0.2794)
						)
					)
					(width 0)
					(fill yes)
				)
			)
		)
		(pad "2" smd custom
			(at 0 0.4445)
			(size 0.1397 0.1397)
			(layers "F.Cu" "F.Mask" "F.Paste")
			(net "VR_PVDDQ_ABC_VINSEN")
			(options
				(clearance outline)
				(anchor circle)
			)
			(primitives
				(gr_poly
					(pts
						(arc
							(start -0.1778 -0.2794)
							(mid -0.249642 -0.249642)
							(end -0.2794 -0.1778)
						)
						(arc
							(start -0.2794 0.1778)
							(mid -0.249642 0.249642)
							(end -0.1778 0.2794)
						)
						(arc
							(start 0.1778 0.2794)
							(mid 0.249642 0.249642)
							(end 0.2794 0.1778)
						)
						(arc
							(start 0.2794 -0.1778)
							(mid 0.249642 -0.249642)
							(end 0.1778 -0.2794)
						)
					)
					(width 0)
					(fill yes)
				)
			)
		)
	)
	(footprint ""
		(layer "F.Cu")
		(at 171.704 -70.6374 180)
		(property "Reference" "C4D32"
			(at 0 0 180)
			(layer "F.SilkS")
			(hide yes)
			(effects
				(font
					(size 1.27 1.27)
				)
			)
		)
		(property "Value" ""
			(at 0 0 180)
			(layer "F.Fab")
			(effects
				(font
					(size 1.27 1.27)
				)
			)
		)
		(duplicate_pad_numbers_are_jumpers no)
		(fp_poly
			(pts
				(xy 0.3048 -0.1016) (xy 0.3048 0.9906) (xy -0.3048 0.9906) (xy -0.3048 -0.1016)
			)
			(stroke
				(width 0)
				(type default)
			)
			(fill no)
			(layer "F.CrtYd")
		)
		(fp_line
			(start 0.3048 0.9906)
			(end 0.3048 -0.1016)
			(stroke
				(width 0.1)
				(type default)
			)
			(layer "F.Fab")
		)
		(fp_line
			(start 0.3048 -0.1016)
			(end -0.3048 -0.1016)
			(stroke
				(width 0.1)
				(type default)
			)
			(layer "F.Fab")
		)
		(fp_line
			(start -0.3048 0.9906)
			(end 0.3048 0.9906)
			(stroke
				(width 0.1)
				(type default)
			)
			(layer "F.Fab")
		)
		(fp_line
			(start -0.3048 -0.1016)
			(end -0.3048 0.9906)
			(stroke
				(width 0.1)
				(type default)
			)
			(layer "F.Fab")
		)
		(pad "1" smd rect
			(at 0 0 180)
			(size 0.508 0.508)
			(layers "F.Cu" "F.Mask" "F.Paste")
			(net "VR_PVCCIO_CPU1_VD12")
		)
		(pad "2" smd rect
			(at 0 0.889 180)
			(size 0.508 0.508)
			(layers "F.Cu" "F.Mask" "F.Paste")
			(net "GND")
		)
		(zone
			(layer "F.Cu")
			(hatch none 0.5)
			(connect_pads
				(clearance 0)
			)
			(min_thickness 0.25)
			(keepout
				(tracks not_allowed)
				(vias allowed)
				(pads allowed)
				(copperpour not_allowed)
				(footprints allowed)
			)
			(placement
				(enabled no)
				(sheetname "")
			)
			(fill
				(thermal_gap 0.5)
				(thermal_bridge_width 0.5)
				(island_removal_mode 0)
			)
			(polygon
				(pts
					(xy 171.958 -71.2724) (xy 171.45 -71.2724) (xy 171.45 -70.8914) (xy 171.958 -70.8914)
				)
			)
		)
		(zone
			(layer "F.Cu")
			(hatch none 0.5)
			(connect_pads
				(clearance 0)
			)
			(min_thickness 0.25)
			(keepout
				(tracks allowed)
				(vias not_allowed)
				(pads allowed)
				(copperpour not_allowed)
				(footprints allowed)
			)
			(placement
				(enabled no)
				(sheetname "")
			)
			(fill
				(thermal_gap 0.5)
				(thermal_bridge_width 0.5)
				(island_removal_mode 0)
			)
			(polygon
				(pts
					(xy 171.958 -70.8914) (xy 171.45 -70.8914) (xy 171.45 -71.2724) (xy 171.958 -71.2724)
				)
			)
		)
	)
)
